(kicad_pcb
	(version 20260206)
	(generator "pcbnew")
	(generator_version "10.0")
	(general
		(thickness 1.6)
		(legacy_teardrops no)
	)
	(paper "A4")
	(title_block
		(title "Wiwynn_Tioga_Pass_MB.brd")
		(comment 1 "Tioga Pass / footprint 2254 of 4770 (U5D1), pads 807-911 of 3647")
	)
	(layers
		(0 "F.Cu" signal "TOP")
		(4 "In1.Cu" signal "L2GND")
		(6 "In2.Cu" signal "L3")
		(8 "In3.Cu" signal "L4GND")
		(10 "In4.Cu" signal "L5")
		(12 "In5.Cu" signal "L6GND")
		(14 "In6.Cu" signal "L7VCC")
		(16 "In7.Cu" signal "L8VCC")
		(18 "In8.Cu" signal "L9GND")
		(20 "In9.Cu" signal "L10")
		(22 "In10.Cu" signal "L11GND")
		(24 "In11.Cu" signal "L12")
		(26 "In12.Cu" signal "L13GND")
		(2 "B.Cu" signal "BOTTOM")
		(9 "F.Adhes" user "F.Adhesive")
		(11 "B.Adhes" user "B.Adhesive")
		(13 "F.Paste" user "Package Geometry/Pastemask Top")
		(15 "B.Paste" user "Package Geometry/Pastemask Bottom")
		(5 "F.SilkS" user "Ref Des/Silkscreen Top")
		(7 "B.SilkS" user "Ref Des/Silkscreen Bottom")
		(1 "F.Mask" user "Board Geometry/Soldermask Top")
		(3 "B.Mask" user "Board Geometry/Soldermask Bottom")
		(17 "Dwgs.User" user "User.Drawings")
		(19 "Cmts.User" user "User.Comments")
		(21 "Eco1.User" user "User.Eco1")
		(23 "Eco2.User" user "User.Eco2")
		(25 "Edge.Cuts" user "Board Geometry/Outline")
		(27 "Margin" user)
		(31 "F.CrtYd" user "Package Geometry/Place Bound Top")
		(29 "B.CrtYd" user "Package Geometry/Place Bound Bottom")
		(35 "F.Fab" user "Ref Des/Assembly Top")
		(33 "B.Fab" user "Ref Des/Assembly Bottom")
	)
	(footprint ""
		(layer "F.Cu")
		(at 270.000222 -76.550012 180)
		(property "Reference" "U5D1"
			(at 19.124422 31.601918 0)
			(unlocked yes)
			(layer "F.SilkS")
			(effects
				(font
					(size 0.7874 0.5842)
					(thickness 0.1524)
				)
			)
		)
		(property "Value" ""
			(at 0 0 180)
			(layer "F.Fab")
			(effects
				(font
					(size 1.27 1.27)
				)
			)
		)
		(duplicate_pad_numbers_are_jumpers no)
		(pad "BB79" smd circle
			(at 31.240984 -6.596126)
			(size 0.4318 0.4318)
			(layers "F.Cu" "F.Mask" "F.Paste")
			(net "GND")
		)
		(pad "BB81" smd circle
			(at 32.958024 -6.596126)
			(size 0.4318 0.4318)
			(layers "F.Cu" "F.Mask" "F.Paste")
			(net "GND")
		)
		(pad "BB83" smd circle
			(at 34.675064 -6.596126)
			(size 0.4318 0.4318)
			(layers "F.Cu" "F.Mask" "F.Paste")
			(net "GND")
		)
		(pad "BB85" smd custom
			(at 36.392104 -6.596126 270)
			(size 0.10795 0.10795)
			(layers "F.Cu" "F.Mask" "F.Paste")
			(net "PVCCIN_CPU0")
			(options
				(clearance outline)
				(anchor circle)
			)
			(primitives
				(gr_poly
					(pts
						(arc
							(start 0.2159 -0.0381)
							(mid 0 -0.254)
							(end -0.2159 -0.0381)
						)
						(arc
							(start -0.2159 0.0381)
							(mid 0 0.254)
							(end 0.2159 0.0381)
						)
					)
					(width 0)
					(fill yes)
				)
			)
		)
		(pad "BC2" smd custom
			(at -36.392104 -4.300474 90)
			(size 0.10795 0.10795)
			(layers "F.Cu" "F.Mask" "F.Paste")
			(net "UPI_CPU0_CPU1_P0P0_DP<2>")
			(options
				(clearance outline)
				(anchor circle)
			)
			(primitives
				(gr_poly
					(pts
						(arc
							(start 0.2159 -0.0381)
							(mid 0 -0.254)
							(end -0.2159 -0.0381)
						)
						(arc
							(start -0.2159 0.0381)
							(mid 0 0.254)
							(end 0.2159 0.0381)
						)
					)
					(width 0)
					(fill yes)
				)
			)
		)
		(pad "BC4" smd circle
			(at -34.675064 -4.300474)
			(size 0.4318 0.4318)
			(layers "F.Cu" "F.Mask" "F.Paste")
			(net "GND")
		)
		(pad "BC6" smd circle
			(at -32.958024 -4.300474)
			(size 0.4318 0.4318)
			(layers "F.Cu" "F.Mask" "F.Paste")
			(net "UPI_CPU1_CPU0_P0P0_DN<5>")
		)
		(pad "BC8" smd circle
			(at -31.240984 -4.300474)
			(size 0.4318 0.4318)
			(layers "F.Cu" "F.Mask" "F.Paste")
			(net "GND")
		)
		(pad "BC10" smd circle
			(at -29.523944 -4.300474)
			(size 0.4318 0.4318)
			(layers "F.Cu" "F.Mask" "F.Paste")
			(net "UPI_CPU1_CPU0_P0P0_DP<1>")
		)
		(pad "BC12" smd circle
			(at -27.806904 -4.300474)
			(size 0.4318 0.4318)
			(layers "F.Cu" "F.Mask" "F.Paste")
			(net "GND")
		)
		(pad "BC14" smd circle
			(at -26.090118 -4.300474)
			(size 0.4318 0.4318)
			(layers "F.Cu" "F.Mask" "F.Paste")
			(net "TP_CPU0_RSVD_162")
		)
		(pad "BC16" smd circle
			(at -24.373078 -4.300474)
			(size 0.4318 0.4318)
			(layers "F.Cu" "F.Mask" "F.Paste")
			(net "GND")
		)
		(pad "BC18" smd circle
			(at -22.656038 -4.300474)
			(size 0.4318 0.4318)
			(layers "F.Cu" "F.Mask" "F.Paste")
			(net "TP_CPU0_RSVD_161")
		)
		(pad "BC20" smd circle
			(at -20.938998 -4.300474)
			(size 0.4318 0.4318)
			(layers "F.Cu" "F.Mask" "F.Paste")
			(net "TP_CPU0_RSVD_160")
		)
		(pad "BC22" smd circle
			(at -19.221958 -4.300474)
			(size 0.4318 0.4318)
			(layers "F.Cu" "F.Mask" "F.Paste")
			(net "TP_CPU0_RSVD_159")
		)
		(pad "BC24" smd circle
			(at -17.504918 -4.300474)
			(size 0.4318 0.4318)
			(layers "F.Cu" "F.Mask" "F.Paste")
			(net "PWRGD_CPU0_G")
		)
		(pad "BC26" smd circle
			(at -15.787878 -4.300474)
			(size 0.4318 0.4318)
			(layers "F.Cu" "F.Mask" "F.Paste")
			(net "PVCCIO_CPU0")
		)
		(pad "BC60" smd circle
			(at 14.929612 -6.100572)
			(size 0.508 0.508)
			(layers "F.Cu" "F.Mask" "F.Paste")
			(net "PVCCIN_CPU0")
		)
		(pad "BC62" smd circle
			(at 16.646398 -6.100572)
			(size 0.4318 0.4318)
			(layers "F.Cu" "F.Mask" "F.Paste")
			(net "PVCCIN_CPU0")
		)
		(pad "BC64" smd circle
			(at 18.363438 -6.100572)
			(size 0.4318 0.4318)
			(layers "F.Cu" "F.Mask" "F.Paste")
			(net "TP_CPU0_RSVD_158")
		)
		(pad "BC66" smd circle
			(at 20.080478 -6.100572)
			(size 0.4318 0.4318)
			(layers "F.Cu" "F.Mask" "F.Paste")
			(net "TP_CPU0_RSVD_157")
		)
		(pad "BC68" smd circle
			(at 21.797518 -6.100572)
			(size 0.4318 0.4318)
			(layers "F.Cu" "F.Mask" "F.Paste")
			(net "TP_CPU0_RSVD_156")
		)
		(pad "BC70" smd circle
			(at 23.514558 -6.100572)
			(size 0.4318 0.4318)
			(layers "F.Cu" "F.Mask" "F.Paste")
			(net "GND")
		)
		(pad "BC72" smd circle
			(at 25.231598 -6.100572)
			(size 0.4318 0.4318)
			(layers "F.Cu" "F.Mask" "F.Paste")
			(net "GND")
		)
		(pad "BC74" smd circle
			(at 26.948384 -6.100572)
			(size 0.4318 0.4318)
			(layers "F.Cu" "F.Mask" "F.Paste")
			(net "GND")
		)
		(pad "BC76" smd circle
			(at 28.665424 -6.100572)
			(size 0.4318 0.4318)
			(layers "F.Cu" "F.Mask" "F.Paste")
			(net "GND")
		)
		(pad "BC78" smd circle
			(at 30.382464 -6.100572)
			(size 0.4318 0.4318)
			(layers "F.Cu" "F.Mask" "F.Paste")
			(net "GND")
		)
		(pad "BC80" smd circle
			(at 32.099504 -6.100572)
			(size 0.4318 0.4318)
			(layers "F.Cu" "F.Mask" "F.Paste")
			(net "GND")
		)
		(pad "BC82" smd circle
			(at 33.816544 -6.100572)
			(size 0.4318 0.4318)
			(layers "F.Cu" "F.Mask" "F.Paste")
			(net "GND")
		)
		(pad "BC84" smd circle
			(at 35.533584 -6.100572)
			(size 0.4318 0.4318)
			(layers "F.Cu" "F.Mask" "F.Paste")
			(net "PVCCIN_CPU0")
		)
		(pad "BD3" smd custom
			(at -35.533584 -3.805428 90)
			(size 0.10795 0.10795)
			(layers "F.Cu" "F.Mask" "F.Paste")
			(net "UPI_CPU0_CPU1_P0P0_DP<1>")
			(options
				(clearance outline)
				(anchor circle)
			)
			(primitives
				(gr_poly
					(pts
						(arc
							(start 0.2159 -0.0381)
							(mid 0 -0.254)
							(end -0.2159 -0.0381)
						)
						(arc
							(start -0.2159 0.0381)
							(mid 0 0.254)
							(end 0.2159 0.0381)
						)
					)
					(width 0)
					(fill yes)
				)
			)
		)
		(pad "BD5" smd circle
			(at -33.816544 -3.805428)
			(size 0.4318 0.4318)
			(layers "F.Cu" "F.Mask" "F.Paste")
			(net "GND")
		)
		(pad "BD7" smd circle
			(at -32.099504 -3.805428)
			(size 0.4318 0.4318)
			(layers "F.Cu" "F.Mask" "F.Paste")
			(net "UPI_CPU1_CPU0_P0P0_DN<4>")
		)
		(pad "BD9" smd circle
			(at -30.382464 -3.805428)
			(size 0.4318 0.4318)
			(layers "F.Cu" "F.Mask" "F.Paste")
			(net "UPI_CPU1_CPU0_P0P0_DN<1>")
		)
		(pad "BD11" smd circle
			(at -28.665424 -3.805428)
			(size 0.4318 0.4318)
			(layers "F.Cu" "F.Mask" "F.Paste")
			(net "GND")
		)
		(pad "BD13" smd circle
			(at -26.948384 -3.805428)
			(size 0.4318 0.4318)
			(layers "F.Cu" "F.Mask" "F.Paste")
			(net "PVCCMCP_CPU0")
		)
		(pad "BD15" smd circle
			(at -25.231598 -3.805428)
			(size 0.4318 0.4318)
			(layers "F.Cu" "F.Mask" "F.Paste")
			(net "GND")
		)
		(pad "BD17" smd circle
			(at -23.514558 -3.805428)
			(size 0.4318 0.4318)
			(layers "F.Cu" "F.Mask" "F.Paste")
			(net "TP_CPU0_RSVD_155")
		)
		(pad "BD19" smd circle
			(at -21.797518 -3.805428)
			(size 0.4318 0.4318)
			(layers "F.Cu" "F.Mask" "F.Paste")
			(net "TP_CPU0_RSVD_154")
		)
		(pad "BD21" smd circle
			(at -20.080478 -3.805428)
			(size 0.4318 0.4318)
			(layers "F.Cu" "F.Mask" "F.Paste")
			(net "GND")
		)
		(pad "BD23" smd circle
			(at -18.363438 -3.805428)
			(size 0.4318 0.4318)
			(layers "F.Cu" "F.Mask" "F.Paste")
			(net "H_CPU0_BMCINIT")
		)
		(pad "BD25" smd circle
			(at -16.646398 -3.805428)
			(size 0.4318 0.4318)
			(layers "F.Cu" "F.Mask" "F.Paste")
			(net "CLK_100M_CPU0_RC_REFCLK1_DP")
		)
		(pad "BD27" smd circle
			(at -14.929612 -3.805428)
			(size 0.4318 0.4318)
			(layers "F.Cu" "F.Mask" "F.Paste")
			(net "GND")
		)
		(pad "BD61" smd circle
			(at 15.787878 -5.605272)
			(size 0.4318 0.4318)
			(layers "F.Cu" "F.Mask" "F.Paste")
			(net "PVCCIN_CPU0")
		)
		(pad "BD63" smd circle
			(at 17.504918 -5.605272)
			(size 0.4318 0.4318)
			(layers "F.Cu" "F.Mask" "F.Paste")
			(net "GND")
		)
		(pad "BD65" smd circle
			(at 19.221958 -5.605272)
			(size 0.4318 0.4318)
			(layers "F.Cu" "F.Mask" "F.Paste")
			(net "TP_CPU0_RSVD_152")
		)
		(pad "BD67" smd circle
			(at 20.938998 -5.605272)
			(size 0.4318 0.4318)
			(layers "F.Cu" "F.Mask" "F.Paste")
			(net "TP_CPU0_RSVD_151")
		)
		(pad "BD69" smd circle
			(at 22.656038 -5.605272)
			(size 0.4318 0.4318)
			(layers "F.Cu" "F.Mask" "F.Paste")
			(net "TP_CPU0_RSVD_150")
		)
		(pad "BD71" smd circle
			(at 24.373078 -5.605272)
			(size 0.4318 0.4318)
			(layers "F.Cu" "F.Mask" "F.Paste")
			(net "GND")
		)
		(pad "BD73" smd circle
			(at 26.090118 -5.605272)
			(size 0.4318 0.4318)
			(layers "F.Cu" "F.Mask" "F.Paste")
			(net "PVCCIN_CPU0")
		)
		(pad "BD75" smd circle
			(at 27.806904 -5.605272)
			(size 0.4318 0.4318)
			(layers "F.Cu" "F.Mask" "F.Paste")
			(net "PVCCIN_CPU0")
		)
		(pad "BD77" smd circle
			(at 29.523944 -5.605272)
			(size 0.4318 0.4318)
			(layers "F.Cu" "F.Mask" "F.Paste")
			(net "PVCCIN_CPU0")
		)
		(pad "BD79" smd circle
			(at 31.240984 -5.605272)
			(size 0.4318 0.4318)
			(layers "F.Cu" "F.Mask" "F.Paste")
			(net "PVCCIN_CPU0")
		)
		(pad "BD81" smd circle
			(at 32.958024 -5.605272)
			(size 0.4318 0.4318)
			(layers "F.Cu" "F.Mask" "F.Paste")
			(net "PVCCIN_CPU0")
		)
		(pad "BD83" smd circle
			(at 34.675064 -5.605272)
			(size 0.4318 0.4318)
			(layers "F.Cu" "F.Mask" "F.Paste")
			(net "PVCCIN_CPU0")
		)
		(pad "BD85" smd custom
			(at 36.392104 -5.605272 270)
			(size 0.10795 0.10795)
			(layers "F.Cu" "F.Mask" "F.Paste")
			(net "PVCCIN_CPU0")
			(options
				(clearance outline)
				(anchor circle)
			)
			(primitives
				(gr_poly
					(pts
						(arc
							(start 0.2159 -0.0381)
							(mid 0 -0.254)
							(end -0.2159 -0.0381)
						)
						(arc
							(start -0.2159 0.0381)
							(mid 0 0.254)
							(end 0.2159 0.0381)
						)
					)
					(width 0)
					(fill yes)
				)
			)
		)
		(pad "BE4" smd circle
			(at -34.675064 -3.309874)
			(size 0.4318 0.4318)
			(layers "F.Cu" "F.Mask" "F.Paste")
			(net "GND")
		)
		(pad "BE6" smd circle
			(at -32.958024 -3.309874)
			(size 0.4318 0.4318)
			(layers "F.Cu" "F.Mask" "F.Paste")
			(net "GND")
		)
		(pad "BE8" smd circle
			(at -31.240984 -3.309874)
			(size 0.4318 0.4318)
			(layers "F.Cu" "F.Mask" "F.Paste")
			(net "GND")
		)
		(pad "BE10" smd circle
			(at -29.523944 -3.309874)
			(size 0.4318 0.4318)
			(layers "F.Cu" "F.Mask" "F.Paste")
			(net "GND")
		)
		(pad "BE12" smd circle
			(at -27.806904 -3.309874)
			(size 0.4318 0.4318)
			(layers "F.Cu" "F.Mask" "F.Paste")
			(net "PVCCMCP_CPU0")
		)
		(pad "BE14" smd circle
			(at -26.090118 -3.309874)
			(size 0.4318 0.4318)
			(layers "F.Cu" "F.Mask" "F.Paste")
			(net "PVCCMCP_CPU0")
		)
		(pad "BE16" smd circle
			(at -24.373078 -3.309874)
			(size 0.4318 0.4318)
			(layers "F.Cu" "F.Mask" "F.Paste")
			(net "CLK_156M_OSC_CPU0_HFI_DN")
		)
		(pad "BE18" smd circle
			(at -22.656038 -3.309874)
			(size 0.4318 0.4318)
			(layers "F.Cu" "F.Mask" "F.Paste")
			(net "TP_CPU0_RSVD_149")
		)
		(pad "BE20" smd circle
			(at -20.938998 -3.309874)
			(size 0.4318 0.4318)
			(layers "F.Cu" "F.Mask" "F.Paste")
			(net "TP_CPU0_RSVD_148")
		)
		(pad "BE22" smd circle
			(at -19.221958 -3.309874)
			(size 0.4318 0.4318)
			(layers "F.Cu" "F.Mask" "F.Paste")
			(net "TP_CPU0_RSVD_147")
		)
		(pad "BE24" smd circle
			(at -17.504918 -3.309874)
			(size 0.4318 0.4318)
			(layers "F.Cu" "F.Mask" "F.Paste")
			(net "PVCCIO_CPU0")
		)
		(pad "BE26" smd circle
			(at -15.787878 -3.309874)
			(size 0.4318 0.4318)
			(layers "F.Cu" "F.Mask" "F.Paste")
			(net "GND")
		)
		(pad "BE60" smd circle
			(at 14.929612 -5.109972)
			(size 0.508 0.508)
			(layers "F.Cu" "F.Mask" "F.Paste")
			(net "PVCCIN_CPU0")
		)
		(pad "BE62" smd circle
			(at 16.646398 -5.109972)
			(size 0.4318 0.4318)
			(layers "F.Cu" "F.Mask" "F.Paste")
			(net "PVCCIN_CPU0")
		)
		(pad "BE64" smd circle
			(at 18.363438 -5.109972)
			(size 0.4318 0.4318)
			(layers "F.Cu" "F.Mask" "F.Paste")
			(net "GND")
		)
		(pad "BE66" smd circle
			(at 20.080478 -5.109972)
			(size 0.4318 0.4318)
			(layers "F.Cu" "F.Mask" "F.Paste")
			(net "GND")
		)
		(pad "BE68" smd circle
			(at 21.797518 -5.109972)
			(size 0.4318 0.4318)
			(layers "F.Cu" "F.Mask" "F.Paste")
			(net "GND")
		)
		(pad "BE70" smd circle
			(at 23.514558 -5.109972)
			(size 0.4318 0.4318)
			(layers "F.Cu" "F.Mask" "F.Paste")
			(net "GND")
		)
		(pad "BE72" smd circle
			(at 25.231598 -5.109972)
			(size 0.4318 0.4318)
			(layers "F.Cu" "F.Mask" "F.Paste")
			(net "PVCCIN_CPU0")
		)
		(pad "BE74" smd circle
			(at 26.948384 -5.109972)
			(size 0.4318 0.4318)
			(layers "F.Cu" "F.Mask" "F.Paste")
			(net "PVCCIN_CPU0")
		)
		(pad "BE76" smd circle
			(at 28.665424 -5.109972)
			(size 0.4318 0.4318)
			(layers "F.Cu" "F.Mask" "F.Paste")
			(net "PVCCIN_CPU0")
		)
		(pad "BE78" smd circle
			(at 30.382464 -5.109972)
			(size 0.4318 0.4318)
			(layers "F.Cu" "F.Mask" "F.Paste")
			(net "PVCCIN_CPU0")
		)
		(pad "BE80" smd circle
			(at 32.099504 -5.109972)
			(size 0.4318 0.4318)
			(layers "F.Cu" "F.Mask" "F.Paste")
			(net "PVCCIN_CPU0")
		)
		(pad "BE82" smd circle
			(at 33.816544 -5.109972)
			(size 0.4318 0.4318)
			(layers "F.Cu" "F.Mask" "F.Paste")
			(net "PVCCIN_CPU0")
		)
		(pad "BE84" smd circle
			(at 35.533584 -5.109972)
			(size 0.4318 0.4318)
			(layers "F.Cu" "F.Mask" "F.Paste")
			(net "PVCCIN_CPU0")
		)
		(pad "BF3" smd custom
			(at -35.533584 -2.814828 90)
			(size 0.10795 0.10795)
			(layers "F.Cu" "F.Mask" "F.Paste")
			(net "UPI_CPU0_CPU1_P0P0_DN<1>")
			(options
				(clearance outline)
				(anchor circle)
			)
			(primitives
				(gr_poly
					(pts
						(arc
							(start 0.2159 -0.0381)
							(mid 0 -0.254)
							(end -0.2159 -0.0381)
						)
						(arc
							(start -0.2159 0.0381)
							(mid 0 0.254)
							(end 0.2159 0.0381)
						)
					)
					(width 0)
					(fill yes)
				)
			)
		)
		(pad "BF5" smd circle
			(at -33.816544 -2.814828)
			(size 0.4318 0.4318)
			(layers "F.Cu" "F.Mask" "F.Paste")
			(net "VSENSE_PVCCIO_CPU0_SKT_VRTN")
		)
		(pad "BF7" smd circle
			(at -32.099504 -2.814828)
			(size 0.4318 0.4318)
			(layers "F.Cu" "F.Mask" "F.Paste")
			(net "UPI_CPU1_CPU0_P0P0_DP<4>")
		)
		(pad "BF9" smd circle
			(at -30.382464 -2.814828)
			(size 0.4318 0.4318)
			(layers "F.Cu" "F.Mask" "F.Paste")
			(net "GND")
		)
		(pad "BF11" smd circle
			(at -28.665424 -2.814828)
			(size 0.4318 0.4318)
			(layers "F.Cu" "F.Mask" "F.Paste")
			(net "PVCCMCP_CPU0")
		)
		(pad "BF13" smd circle
			(at -26.948384 -2.814828)
			(size 0.4318 0.4318)
			(layers "F.Cu" "F.Mask" "F.Paste")
			(net "PVCCMCP_CPU0")
		)
		(pad "BF15" smd circle
			(at -25.231598 -2.814828)
			(size 0.4318 0.4318)
			(layers "F.Cu" "F.Mask" "F.Paste")
			(net "GND")
		)
		(pad "BF17" smd circle
			(at -23.514558 -2.814828)
			(size 0.4318 0.4318)
			(layers "F.Cu" "F.Mask" "F.Paste")
			(net "GND")
		)
		(pad "BF19" smd circle
			(at -21.797518 -2.814828)
			(size 0.4318 0.4318)
			(layers "F.Cu" "F.Mask" "F.Paste")
			(net "GND")
		)
		(pad "BF21" smd circle
			(at -20.080478 -2.814828)
			(size 0.4318 0.4318)
			(layers "F.Cu" "F.Mask" "F.Paste")
			(net "TP_CPU0_RSVD_146")
		)
		(pad "BF23" smd circle
			(at -18.363438 -2.814828)
			(size 0.4318 0.4318)
			(layers "F.Cu" "F.Mask" "F.Paste")
			(net "PVCCIO_CPU0")
		)
		(pad "BF25" smd circle
			(at -16.646398 -2.814828)
			(size 0.4318 0.4318)
			(layers "F.Cu" "F.Mask" "F.Paste")
			(net "GND")
		)
		(pad "BF27" smd circle
			(at -14.929612 -2.814828)
			(size 0.4318 0.4318)
			(layers "F.Cu" "F.Mask" "F.Paste")
			(net "PVCCIO_CPU0")
		)
		(pad "BF61" smd circle
			(at 15.787878 -4.614926)
			(size 0.4318 0.4318)
			(layers "F.Cu" "F.Mask" "F.Paste")
			(net "PVCCIN_CPU0")
		)
		(pad "BF63" smd circle
			(at 17.504918 -4.614926)
			(size 0.4318 0.4318)
			(layers "F.Cu" "F.Mask" "F.Paste")
			(net "GND")
		)
		(pad "BF65" smd circle
			(at 19.221958 -4.614926)
			(size 0.4318 0.4318)
			(layers "F.Cu" "F.Mask" "F.Paste")
			(net "GND")
		)
		(pad "BF67" smd circle
			(at 20.938998 -4.614926)
			(size 0.4318 0.4318)
			(layers "F.Cu" "F.Mask" "F.Paste")
			(net "GND")
		)
		(pad "BF69" smd circle
			(at 22.656038 -4.614926)
			(size 0.4318 0.4318)
			(layers "F.Cu" "F.Mask" "F.Paste")
			(net "GND")
		)
		(pad "BF71" smd circle
			(at 24.373078 -4.614926)
			(size 0.4318 0.4318)
			(layers "F.Cu" "F.Mask" "F.Paste")
			(net "GND")
		)
		(pad "BF73" smd circle
			(at 26.090118 -4.614926)
			(size 0.4318 0.4318)
			(layers "F.Cu" "F.Mask" "F.Paste")
			(net "PVCCIN_CPU0")
		)
		(pad "BF75" smd circle
			(at 27.806904 -4.614926)
			(size 0.4318 0.4318)
			(layers "F.Cu" "F.Mask" "F.Paste")
			(net "PVCCIN_CPU0")
		)
		(pad "BF77" smd circle
			(at 29.523944 -4.614926)
			(size 0.4318 0.4318)
			(layers "F.Cu" "F.Mask" "F.Paste")
			(net "PVCCIN_CPU0")
		)
		(pad "BF79" smd circle
			(at 31.240984 -4.614926)
			(size 0.4318 0.4318)
			(layers "F.Cu" "F.Mask" "F.Paste")
			(net "PVCCIN_CPU0")
		)
		(pad "BF81" smd circle
			(at 32.958024 -4.614926)
			(size 0.4318 0.4318)
			(layers "F.Cu" "F.Mask" "F.Paste")
			(net "PVCCIN_CPU0")
		)
	)
)
